# T6G (Grand Teton) — schematic netlist excerpt (pin names and nets, part order shuffled) for the footprints in the layout excerpt that follows; sources: Cadence DE-HDL packaged netlist, KiCad conversion of 04192023_DAF0TMB3IC0_F0TG_MB_C_brd_V02_OCP.brd

R1586  Q_RES  49.9 1% CHIP  pkg 0402LF  page 104 : A = I3C_SPD_DDRGL_CPU1_SCL ; B = I3C_SPD_DDRG_CPU1_SCL
PC245  Q_CAP  3300PF 50V 10% X7R  pkg 0402  page 210 : A = VSENSE_PVDDCR_SOC_P1_VSEN1 ; B = VSENSE_VSS_SENSE_A_P1

(kicad_pcb
	(version 20260206)
	(generator "pcbnew")
	(generator_version "10.0")
	(general
		(thickness 1.6)
		(legacy_teardrops no)
	)
	(paper "A4")
	(title_block
		(title "04192023_DAF0TMB3IC0_F0TG_MB_C_brd_V02_OCP.brd")
		(comment 1 "Grand Teton / footprints 7145-7146 of 8354")
	)
	(layers
		(0 "F.Cu" signal "TOP")
		(4 "In1.Cu" signal "GND")
		(6 "In2.Cu" signal "IN1")
		(8 "In3.Cu" signal "GND1")
		(10 "In4.Cu" signal "IN2")
		(12 "In5.Cu" signal "GND2")
		(14 "In6.Cu" signal "IN3")
		(16 "In7.Cu" signal "GND3")
		(18 "In8.Cu" signal "VCC")
		(20 "In9.Cu" signal "VCC1")
		(22 "In10.Cu" signal "GND4")
		(24 "In11.Cu" signal "IN4")
		(26 "In12.Cu" signal "GND5")
		(28 "In13.Cu" signal "IN5")
		(30 "In14.Cu" signal "GND6")
		(32 "In15.Cu" signal "IN6")
		(34 "In16.Cu" signal "GND7")
		(2 "B.Cu" signal "BOTTOM")
		(9 "F.Adhes" user "F.Adhesive")
		(11 "B.Adhes" user "B.Adhesive")
		(13 "F.Paste" user "Package Geometry/Pastemask Top")
		(15 "B.Paste" user "Package Geometry/Pastemask Bottom")
		(5 "F.SilkS" user "Ref Des/Silkscreen Top")
		(7 "B.SilkS" user "Ref Des/Silkscreen Bottom")
		(1 "F.Mask" user "Board Geometry/Soldermask Top")
		(3 "B.Mask" user "Board Geometry/Soldermask Bottom")
		(17 "Dwgs.User" user "User.Drawings")
		(19 "Cmts.User" user "User.Comments")
		(21 "Eco1.User" user "User.Eco1")
		(23 "Eco2.User" user "User.Eco2")
		(25 "Edge.Cuts" user "Board Geometry/Outline")
		(27 "Margin" user)
		(31 "F.CrtYd" user "Package Geometry/Place Bound Top")
		(29 "B.CrtYd" user "Package Geometry/Place Bound Bottom")
		(35 "F.Fab" user "Ref Des/Assembly Top")
		(33 "B.Fab" user "Ref Des/Assembly Bottom")
	)
	(footprint ""
		(layer "B.Cu")
		(at 101.004878 -147.04441 -90)
		(property "Reference" "PC245"
			(at 0 0 90)
			(layer "B.SilkS")
			(hide yes)
			(effects
				(font
					(size 1.27 1.27)
				)
				(justify mirror)
			)
		)
		(property "Value" ""
			(at 0 0 90)
			(layer "B.Fab")
			(effects
				(font
					(size 1.27 1.27)
				)
				(justify mirror)
			)
		)
		(duplicate_pad_numbers_are_jumpers no)
		(fp_line
			(start -0.7874 0.4064)
			(end 0.7874 0.4064)
			(stroke
				(width 0.1524)
				(type default)
			)
			(layer "B.SilkS")
		)
		(fp_line
			(start 0.7874 0.4064)
			(end 0.7874 -0.4064)
			(stroke
				(width 0.1524)
				(type default)
			)
			(layer "B.SilkS")
		)
		(fp_line
			(start -0.7874 -0.4064)
			(end -0.7874 0.4064)
			(stroke
				(width 0.1524)
				(type default)
			)
			(layer "B.SilkS")
		)
		(fp_line
			(start 0.7874 -0.4064)
			(end -0.7874 -0.4064)
			(stroke
				(width 0.1524)
				(type default)
			)
			(layer "B.SilkS")
		)
		(fp_line
			(start -0.67945 0.3048)
			(end -0.120396 0.3048)
			(stroke
				(width 0.1)
				(type default)
			)
			(layer "B.Fab")
		)
		(fp_line
			(start -0.120396 0.3048)
			(end -0.120396 0.2794)
			(stroke
				(width 0.1)
				(type default)
			)
			(layer "B.Fab")
		)
		(fp_line
			(start 0.12065 0.3048)
			(end 0.67945 0.3048)
			(stroke
				(width 0.1)
				(type default)
			)
			(layer "B.Fab")
		)
		(fp_line
			(start 0.67945 0.3048)
			(end 0.67945 -0.305054)
			(stroke
				(width 0.1)
				(type default)
			)
			(layer "B.Fab")
		)
		(fp_line
			(start -0.120396 0.2794)
			(end 0.12065 0.2794)
			(stroke
				(width 0.1)
				(type default)
			)
			(layer "B.Fab")
		)
		(fp_line
			(start 0.12065 0.2794)
			(end 0.12065 0.3048)
			(stroke
				(width 0.1)
				(type default)
			)
			(layer "B.Fab")
		)
		(fp_line
			(start -0.12065 -0.2794)
			(end -0.12065 -0.3048)
			(stroke
				(width 0.1)
				(type default)
			)
			(layer "B.Fab")
		)
		(fp_line
			(start 0.12065 -0.2794)
			(end -0.12065 -0.2794)
			(stroke
				(width 0.1)
				(type default)
			)
			(layer "B.Fab")
		)
		(fp_line
			(start -0.67945 -0.3048)
			(end -0.67945 0.3048)
			(stroke
				(width 0.1)
				(type default)
			)
			(layer "B.Fab")
		)
		(fp_line
			(start -0.12065 -0.3048)
			(end -0.67945 -0.3048)
			(stroke
				(width 0.1)
				(type default)
			)
			(layer "B.Fab")
		)
		(fp_line
			(start 0.12065 -0.305054)
			(end 0.12065 -0.2794)
			(stroke
				(width 0.1)
				(type default)
			)
			(layer "B.Fab")
		)
		(fp_line
			(start 0.67945 -0.305054)
			(end 0.12065 -0.305054)
			(stroke
				(width 0.1)
				(type default)
			)
			(layer "B.Fab")
		)
		(pad "1" smd circle
			(at 0.40005 0 90)
			(size 0 0)
			(layers "B.Cu" "B.Mask" "B.Paste")
			(net "VSENSE_PVDDCR_SOC_P1_VSEN1")
		)
		(pad "2" smd circle
			(at -0.40005 0 90)
			(size 0 0)
			(layers "B.Cu" "B.Mask" "B.Paste")
			(net "VSENSE_VSS_SENSE_A_P1")
		)
	)
	(footprint ""
		(layer "B.Cu")
		(at 167.772588 -194.8942 180)
		(property "Reference" "R1586"
			(at 0 0 0)
			(layer "B.SilkS")
			(hide yes)
			(effects
				(font
					(size 1.27 1.27)
				)
				(justify mirror)
			)
		)
		(property "Value" ""
			(at 0 0 0)
			(layer "B.Fab")
			(effects
				(font
					(size 1.27 1.27)
				)
				(justify mirror)
			)
		)
		(duplicate_pad_numbers_are_jumpers no)
		(fp_line
			(start 0.7874 0.4064)
			(end 0.7874 -0.4064)
			(stroke
				(width 0.1524)
				(type default)
			)
			(layer "B.SilkS")
		)
		(fp_line
			(start 0.7874 -0.4064)
			(end -0.7874 -0.4064)
			(stroke
				(width 0.1524)
				(type default)
			)
			(layer "B.SilkS")
		)
		(fp_line
			(start -0.7874 0.4064)
			(end 0.7874 0.4064)
			(stroke
				(width 0.1524)
				(type default)
			)
			(layer "B.SilkS")
		)
		(fp_line
			(start -0.7874 -0.4064)
			(end -0.7874 0.4064)
			(stroke
				(width 0.1524)
				(type default)
			)
			(layer "B.SilkS")
		)
		(fp_line
			(start 0.67945 0.3048)
			(end 0.67945 -0.305054)
			(stroke
				(width 0.1)
				(type default)
			)
			(layer "B.Fab")
		)
		(fp_line
			(start 0.67945 -0.305054)
			(end 0.12065 -0.305054)
			(stroke
				(width 0.1)
				(type default)
			)
			(layer "B.Fab")
		)
		(fp_line
			(start 0.12065 0.3048)
			(end 0.67945 0.3048)
			(stroke
				(width 0.1)
				(type default)
			)
			(layer "B.Fab")
		)
		(fp_line
			(start 0.12065 0.2794)
			(end 0.12065 0.3048)
			(stroke
				(width 0.1)
				(type default)
			)
			(layer "B.Fab")
		)
		(fp_line
			(start 0.12065 -0.2794)
			(end -0.12065 -0.2794)
			(stroke
				(width 0.1)
				(type default)
			)
			(layer "B.Fab")
		)
		(fp_line
			(start 0.12065 -0.305054)
			(end 0.12065 -0.2794)
			(stroke
				(width 0.1)
				(type default)
			)
			(layer "B.Fab")
		)
		(fp_line
			(start -0.120396 0.3048)
			(end -0.120396 0.2794)
			(stroke
				(width 0.1)
				(type default)
			)
			(layer "B.Fab")
		)
		(fp_line
			(start -0.120396 0.2794)
			(end 0.12065 0.2794)
			(stroke
				(width 0.1)
				(type default)
			)
			(layer "B.Fab")
		)
		(fp_line
			(start -0.12065 -0.2794)
			(end -0.12065 -0.3048)
			(stroke
				(width 0.1)
				(type default)
			)
			(layer "B.Fab")
		)
		(fp_line
			(start -0.12065 -0.3048)
			(end -0.67945 -0.3048)
			(stroke
				(width 0.1)
				(type default)
			)
			(layer "B.Fab")
		)
		(fp_line
			(start -0.67945 0.3048)
			(end -0.120396 0.3048)
			(stroke
				(width 0.1)
				(type default)
			)
			(layer "B.Fab")
		)
		(fp_line
			(start -0.67945 -0.3048)
			(end -0.67945 0.3048)
			(stroke
				(width 0.1)
				(type default)
			)
			(layer "B.Fab")
		)
		(pad "1" smd circle
			(at 0.40005 0)
			(size 0 0)
			(layers "B.Cu" "B.Mask" "B.Paste")
			(net "I3C_SPD_DDRGL_CPU1_SCL")
		)
		(pad "2" smd circle
			(at -0.40005 0)
			(size 0 0)
			(layers "B.Cu" "B.Mask" "B.Paste")
			(net "I3C_SPD_DDRG_CPU1_SCL")
		)
	)
)
